FILE_TYPE = CONNECTIVITY;
{Allegro Design Entry HDL 17.2-2016 S081 (4005846) 1/11/2022}
"PAGE_NUMBER" = 120;
0"NC";
1"PVNN_TERM_CPU0\g";
2"PVNN_TERM_CPU1\g";
3"GND\g";
4"GND\g";
5"FM_S3M_CPU1_LVC1_GPIO_1";
6"FM_S3M_CPU1_LVC1_GPIO_3";
7"FM_S3M_CPU1_LVC1_GPIO_4";
8"FM_S3M_CPU1_LVC1_GPIO_3";
9"FM_S3M_CPU0_LVC1_GPIO_3";
10"FM_S3M_CPU0_LVC1_GPIO_2";
11"FM_S3M_CPU0_LVC1_GPIO_3";
12"FM_S3M_CPU0_LVC1_GPIO_2";
13"FM_S3M_CPU1_LVC1_GPIO_2";
14"PUD_PCH_BOOT_MODE_CPU1";
15"FM_S3M_CPU1_LVC1_GPIO_2";
16"PUD_PCH_BOOT_MODE_CPU0";
17"FM_S3M_CPU0_LVC1_GPIO_4";
18"FM_S3M_CPU1_LVC1_GPIO_0";
19"FM_S3M_CPU0_LVC1_GPIO_1";
20"FM_S3M_CPU0_LVC1_GPIO_0";
%"Q_RES"
"1","(-2000,3400)","0","pure_quanta","I27";
;
PART_NUMBER"CS12402FB01"
MATERIAL"EMPTY"
PACK_TYPE"0402LF"
WATTAGE"1/16W"
VALUE"240"
TOLERANCE"1%"
$LOCATION"R249"
CDS_LIB"pure_quanta"
CDS_LOCATION"R249"
$SEC"1"
CDS_SEC"1";
"B"
$PN"2"20;
"A"
$PN"1"1;
%"Q_RES"
"1","(-2000,2900)","0","pure_quanta","I28";
;
PART_NUMBER"CS12402FB01"
MATERIAL"EMPTY"
TOLERANCE"1%"
VALUE"240"
$LOCATION"R251"
CDS_LIB"pure_quanta"
PACK_TYPE"0402LF"
WATTAGE"1/16W"
CDS_LOCATION"R251"
$SEC"1"
CDS_SEC"1";
"B"
$PN"2"17;
"A"
$PN"1"1;
%"Q_RES"
"1","(-2000,3275)","0","pure_quanta","I29";
;
PART_NUMBER"CS12402FB01"
VALUE"240"
TOLERANCE"1%"
MATERIAL"EMPTY"
$LOCATION"R250"
WATTAGE"1/16W"
PACK_TYPE"0402LF"
CDS_LIB"pure_quanta"
CDS_LOCATION"R250"
$SEC"1"
CDS_SEC"1";
"B"
$PN"2"19;
"A"
$PN"1"1;
%"Q_RES"
"1","(-2000,2775)","0","pure_quanta","I30";
;
PART_NUMBER"CS12402FB01"
VALUE"240"
TOLERANCE"1%"
MATERIAL"CHIP"
$LOCATION"R252"
WATTAGE"1/16W"
PACK_TYPE"0402LF"
CDS_LIB"pure_quanta"
CDS_LOCATION"R252"
$SEC"1"
CDS_SEC"1";
"B"
$PN"2"16;
"A"
$PN"1"1;
%"Q_RES"
"1","(-2000,2650)","0","pure_quanta","I31";
;
PART_NUMBER"CS12402FB01"
VALUE"240"
TOLERANCE"1%"
MATERIAL"CHIP"
$LOCATION"R253"
PACK_TYPE"0402LF"
WATTAGE"1/16W"
CDS_LIB"pure_quanta"
CDS_LOCATION"R253"
$SEC"1"
CDS_SEC"1";
"B"
$PN"2"12;
"A"
$PN"1"1;
%"Q_RES"
"1","(-2000,2525)","0","pure_quanta","I32";
;
PART_NUMBER"CS12402FB01"
TOLERANCE"1%"
VALUE"240"
MATERIAL"CHIP"
$LOCATION"R254"
WATTAGE"1/16W"
PACK_TYPE"0402LF"
CDS_LIB"pure_quanta"
CDS_LOCATION"R254"
$SEC"1"
CDS_SEC"1";
"B"
$PN"2"11;
"A"
$PN"1"1;
%"UNIVERSAL_POWER"
"1","(-2300,1150)","0","logical_power","I41";
;
HDL_POWER"PVNN_TERM_CPU1"
CDS_LIB"logical_power";
"A"2;
%"Q_RES"
"1","(-2000,900)","0","pure_quanta","I42";
;
PART_NUMBER"CS12402FB01"
VALUE"240"
TOLERANCE"1%"
PACK_TYPE"0402LF"
WATTAGE"1/16W"
MATERIAL"EMPTY"
$LOCATION"R255"
CDS_LIB"pure_quanta"
CDS_LOCATION"R255"
$SEC"1"
CDS_SEC"1";
"B"
$PN"2"18;
"A"
$PN"1"2;
%"Q_RES"
"1","(-2000,400)","0","pure_quanta","I43";
;
PART_NUMBER"CS12402FB01"
MATERIAL"EMPTY"
TOLERANCE"1%"
VALUE"240"
$LOCATION"R257"
CDS_LIB"pure_quanta"
WATTAGE"1/16W"
PACK_TYPE"0402LF"
CDS_LOCATION"R257"
$SEC"1"
CDS_SEC"1";
"B"
$PN"2"7;
"A"
$PN"1"2;
%"Q_RES"
"1","(-2000,275)","0","pure_quanta","I44";
;
PART_NUMBER"CS12402FB01"
VALUE"240"
TOLERANCE"1%"
MATERIAL"CHIP"
$LOCATION"R258"
PACK_TYPE"0402LF"
WATTAGE"1/16W"
CDS_LIB"pure_quanta"
CDS_LOCATION"R258"
$SEC"1"
CDS_SEC"1";
"B"
$PN"2"14;
"A"
$PN"1"2;
%"Q_RES"
"1","(-2000,150)","0","pure_quanta","I45";
;
PART_NUMBER"CS12402FB01"
VALUE"240"
TOLERANCE"1%"
MATERIAL"CHIP"
$LOCATION"R259"
WATTAGE"1/16W"
PACK_TYPE"0402LF"
CDS_LIB"pure_quanta"
CDS_LOCATION"R259"
$SEC"1"
CDS_SEC"1";
"B"
$PN"2"13;
"A"
$PN"1"2;
%"Q_RES"
"1","(-2000,25)","0","pure_quanta","I46";
;
PART_NUMBER"CS12402FB01"
VALUE"240"
TOLERANCE"1%"
MATERIAL"CHIP"
$LOCATION"R260"
WATTAGE"1/16W"
PACK_TYPE"0402LF"
CDS_LIB"pure_quanta"
CDS_LOCATION"R260"
$SEC"1"
CDS_SEC"1";
"B"
$PN"2"8;
"A"
$PN"1"2;
%"Q_RES"
"1","(-2000,775)","0","pure_quanta","I48";
;
PART_NUMBER"CS12402FB01"
MATERIAL"EMPTY"
VALUE"240"
TOLERANCE"1%"
$LOCATION"R256"
CDS_LIB"pure_quanta"
PACK_TYPE"0402LF"
WATTAGE"1/16W"
CDS_LOCATION"R256"
$SEC"1"
CDS_SEC"1";
"B"
$PN"2"5;
"A"
$PN"1"2;
%"UNIVERSAL_GND"
"1","(400,2925)","0","logical_power","I55";
;
CDS_LIB"logical_power"
HDL_POWER"GND";
"A"3;
%"Q_RES"
"1","(700,3200)","0","pure_quanta","I61";
;
PART_NUMBER"CS12402FB01"
TOLERANCE"1%"
VALUE"240"
WATTAGE"1/16W"
MATERIAL"EMPTY"
PACK_TYPE"0402LF"
$LOCATION"R1391"
CDS_LIB"pure_quanta"
CDS_LOCATION"R1391"
$SEC"1"
CDS_SEC"1";
"B"
$PN"2"10;
"A"
$PN"1"3;
%"Q_RES"
"1","(700,3075)","0","pure_quanta","I62";
;
PART_NUMBER"CS12402FB01"
VALUE"240"
MATERIAL"EMPTY"
TOLERANCE"1%"
$LOCATION"R1392"
CDS_LIB"pure_quanta"
PACK_TYPE"0402LF"
WATTAGE"1/16W"
CDS_LOCATION"R1392"
$SEC"1"
CDS_SEC"1";
"B"
$PN"2"9;
"A"
$PN"1"3;
%"UNIVERSAL_GND"
"1","(400,475)","0","logical_power","I63";
;
CDS_LIB"logical_power"
HDL_POWER"GND";
"A"4;
%"Q_RES"
"1","(700,750)","0","pure_quanta","I66";
;
PART_NUMBER"CS12402FB01"
PACK_TYPE"0402LF"
TOLERANCE"1%"
WATTAGE"1/16W"
VALUE"240"
MATERIAL"EMPTY"
$LOCATION"R1393"
CDS_LIB"pure_quanta"
CDS_LOCATION"R1393"
$SEC"1"
CDS_SEC"1";
"B"
$PN"2"15;
"A"
$PN"1"4;
%"Q_RES"
"1","(700,625)","0","pure_quanta","I67";
;
PART_NUMBER"CS12402FB01"
VALUE"240"
TOLERANCE"1%"
MATERIAL"EMPTY"
$LOCATION"R1394"
CDS_LIB"pure_quanta"
PACK_TYPE"0402LF"
WATTAGE"1/16W"
CDS_LOCATION"R1394"
$SEC"1"
CDS_SEC"1";
"B"
$PN"2"6;
"A"
$PN"1"4;
%"UNIVERSAL_POWER"
"1","(-2300,3650)","0","logical_power","I8";
;
HDL_POWER"PVNN_TERM_CPU0"
CDS_LIB"logical_power";
"A"1;
END.
